# S9S_MB_2U (Grand Teton) — schematic netlist excerpt (pin names and nets, part order shuffled) for the footprints in the layout excerpt that follows; sources: Cadence DE-HDL packaged netlist, KiCad conversion of 03242023_DA0F0TMBIJ0_F0T_Motherboard_J_brd_V01_OCP.brd

PR1788  Q_RES  3.3 1% CHIP  pkg 0402LF  page 286 : A = SW_PVCCIN_CPU1_BOOT4 ; B = SW_PVCCIN_CPU1_BOOT4_R
R1292  Q_RES  22 1% CHIP  pkg 0402LF  page 154 : A = NCSI_BMC_RXD0_R ; B = RMII_OCP_BMC_RXD_0

(kicad_pcb
	(version 20260206)
	(generator "pcbnew")
	(generator_version "10.0")
	(general
		(thickness 1.6)
		(legacy_teardrops no)
	)
	(paper "A4")
	(title_block
		(title "03242023_DA0F0TMBIJ0_F0T_Motherboard_J_brd_V01_OCP.brd")
		(comment 1 "Grand Teton / footprints 2127-2128 of 6105")
	)
	(layers
		(0 "F.Cu" signal "TOP")
		(4 "In1.Cu" signal "GND")
		(6 "In2.Cu" signal "IN1")
		(8 "In3.Cu" signal "GND1")
		(10 "In4.Cu" signal "IN2")
		(12 "In5.Cu" signal "GND2")
		(14 "In6.Cu" signal "IN3")
		(16 "In7.Cu" signal "GND3")
		(18 "In8.Cu" signal "VCC")
		(20 "In9.Cu" signal "VCC1")
		(22 "In10.Cu" signal "GND4")
		(24 "In11.Cu" signal "IN4")
		(26 "In12.Cu" signal "GND5")
		(28 "In13.Cu" signal "IN5")
		(30 "In14.Cu" signal "GND6")
		(32 "In15.Cu" signal "IN6")
		(34 "In16.Cu" signal "GND7")
		(2 "B.Cu" signal "BOTTOM")
		(9 "F.Adhes" user "F.Adhesive")
		(11 "B.Adhes" user "B.Adhesive")
		(13 "F.Paste" user "Package Geometry/Pastemask Top")
		(15 "B.Paste" user "Package Geometry/Pastemask Bottom")
		(5 "F.SilkS" user "Ref Des/Silkscreen Top")
		(7 "B.SilkS" user "Ref Des/Silkscreen Bottom")
		(1 "F.Mask" user "Board Geometry/Soldermask Top")
		(3 "B.Mask" user "Board Geometry/Soldermask Bottom")
		(17 "Dwgs.User" user "User.Drawings")
		(19 "Cmts.User" user "User.Comments")
		(21 "Eco1.User" user "User.Eco1")
		(23 "Eco2.User" user "User.Eco2")
		(25 "Edge.Cuts" user "Board Geometry/Outline")
		(27 "Margin" user)
		(31 "F.CrtYd" user "Package Geometry/Place Bound Top")
		(29 "B.CrtYd" user "Package Geometry/Place Bound Bottom")
		(35 "F.Fab" user "Ref Des/Assembly Top")
		(33 "B.Fab" user "Ref Des/Assembly Bottom")
	)
	(footprint ""
		(layer "F.Cu")
		(at 122.238516 -338.17814 90)
		(property "Reference" "PR1788"
			(at 0 0 90)
			(layer "F.SilkS")
			(hide yes)
			(effects
				(font
					(size 1.27 1.27)
				)
			)
		)
		(property "Value" ""
			(at 0 0 90)
			(layer "F.Fab")
			(effects
				(font
					(size 1.27 1.27)
				)
			)
		)
		(duplicate_pad_numbers_are_jumpers no)
		(fp_line
			(start 0.7874 -0.4064)
			(end 0.7874 0.4064)
			(stroke
				(width 0.1524)
				(type default)
			)
			(layer "F.SilkS")
		)
		(fp_line
			(start -0.7874 -0.4064)
			(end 0.7874 -0.4064)
			(stroke
				(width 0.1524)
				(type default)
			)
			(layer "F.SilkS")
		)
		(fp_line
			(start 0.7874 0.4064)
			(end -0.7874 0.4064)
			(stroke
				(width 0.1524)
				(type default)
			)
			(layer "F.SilkS")
		)
		(fp_line
			(start -0.7874 0.4064)
			(end -0.7874 -0.4064)
			(stroke
				(width 0.1524)
				(type default)
			)
			(layer "F.SilkS")
		)
		(fp_line
			(start -0.12065 -0.305054)
			(end -0.12065 -0.2794)
			(stroke
				(width 0.1)
				(type default)
			)
			(layer "F.Fab")
		)
		(fp_line
			(start -0.67945 -0.305054)
			(end -0.12065 -0.305054)
			(stroke
				(width 0.1)
				(type default)
			)
			(layer "F.Fab")
		)
		(fp_line
			(start 0.67945 -0.3048)
			(end 0.67945 0.3048)
			(stroke
				(width 0.1)
				(type default)
			)
			(layer "F.Fab")
		)
		(fp_line
			(start 0.12065 -0.3048)
			(end 0.67945 -0.3048)
			(stroke
				(width 0.1)
				(type default)
			)
			(layer "F.Fab")
		)
		(fp_line
			(start 0.12065 -0.2794)
			(end 0.12065 -0.3048)
			(stroke
				(width 0.1)
				(type default)
			)
			(layer "F.Fab")
		)
		(fp_line
			(start -0.12065 -0.2794)
			(end 0.12065 -0.2794)
			(stroke
				(width 0.1)
				(type default)
			)
			(layer "F.Fab")
		)
		(fp_line
			(start 0.120396 0.2794)
			(end -0.12065 0.2794)
			(stroke
				(width 0.1)
				(type default)
			)
			(layer "F.Fab")
		)
		(fp_line
			(start -0.12065 0.2794)
			(end -0.12065 0.3048)
			(stroke
				(width 0.1)
				(type default)
			)
			(layer "F.Fab")
		)
		(fp_line
			(start 0.67945 0.3048)
			(end 0.120396 0.3048)
			(stroke
				(width 0.1)
				(type default)
			)
			(layer "F.Fab")
		)
		(fp_line
			(start 0.120396 0.3048)
			(end 0.120396 0.2794)
			(stroke
				(width 0.1)
				(type default)
			)
			(layer "F.Fab")
		)
		(fp_line
			(start -0.12065 0.3048)
			(end -0.67945 0.3048)
			(stroke
				(width 0.1)
				(type default)
			)
			(layer "F.Fab")
		)
		(fp_line
			(start -0.67945 0.3048)
			(end -0.67945 -0.305054)
			(stroke
				(width 0.1)
				(type default)
			)
			(layer "F.Fab")
		)
		(pad "1" smd circle
			(at -0.40005 0 90)
			(size 0 0)
			(layers "F.Cu" "F.Mask" "F.Paste")
			(net "SW_PVCCIN_CPU1_BOOT4")
		)
		(pad "2" smd circle
			(at 0.40005 0 90)
			(size 0 0)
			(layers "F.Cu" "F.Mask" "F.Paste")
			(net "SW_PVCCIN_CPU1_BOOT4_R")
		)
	)
	(footprint ""
		(layer "F.Cu")
		(at 200.057004 -77.06614 180)
		(property "Reference" "R1292"
			(at 0 0 180)
			(layer "F.SilkS")
			(hide yes)
			(effects
				(font
					(size 1.27 1.27)
				)
			)
		)
		(property "Value" ""
			(at 0 0 180)
			(layer "F.Fab")
			(effects
				(font
					(size 1.27 1.27)
				)
			)
		)
		(duplicate_pad_numbers_are_jumpers no)
		(fp_line
			(start 0.7874 0.4064)
			(end -0.7874 0.4064)
			(stroke
				(width 0.1524)
				(type default)
			)
			(layer "F.SilkS")
		)
		(fp_line
			(start 0.7874 -0.4064)
			(end 0.7874 0.4064)
			(stroke
				(width 0.1524)
				(type default)
			)
			(layer "F.SilkS")
		)
		(fp_line
			(start -0.7874 0.4064)
			(end -0.7874 -0.4064)
			(stroke
				(width 0.1524)
				(type default)
			)
			(layer "F.SilkS")
		)
		(fp_line
			(start -0.7874 -0.4064)
			(end 0.7874 -0.4064)
			(stroke
				(width 0.1524)
				(type default)
			)
			(layer "F.SilkS")
		)
		(fp_line
			(start 0.67945 0.3048)
			(end 0.120396 0.3048)
			(stroke
				(width 0.1)
				(type default)
			)
			(layer "F.Fab")
		)
		(fp_line
			(start 0.67945 -0.3048)
			(end 0.67945 0.3048)
			(stroke
				(width 0.1)
				(type default)
			)
			(layer "F.Fab")
		)
		(fp_line
			(start 0.12065 -0.2794)
			(end 0.12065 -0.3048)
			(stroke
				(width 0.1)
				(type default)
			)
			(layer "F.Fab")
		)
		(fp_line
			(start 0.12065 -0.3048)
			(end 0.67945 -0.3048)
			(stroke
				(width 0.1)
				(type default)
			)
			(layer "F.Fab")
		)
		(fp_line
			(start 0.120396 0.3048)
			(end 0.120396 0.2794)
			(stroke
				(width 0.1)
				(type default)
			)
			(layer "F.Fab")
		)
		(fp_line
			(start 0.120396 0.2794)
			(end -0.12065 0.2794)
			(stroke
				(width 0.1)
				(type default)
			)
			(layer "F.Fab")
		)
		(fp_line
			(start -0.12065 0.3048)
			(end -0.67945 0.3048)
			(stroke
				(width 0.1)
				(type default)
			)
			(layer "F.Fab")
		)
		(fp_line
			(start -0.12065 0.2794)
			(end -0.12065 0.3048)
			(stroke
				(width 0.1)
				(type default)
			)
			(layer "F.Fab")
		)
		(fp_line
			(start -0.12065 -0.2794)
			(end 0.12065 -0.2794)
			(stroke
				(width 0.1)
				(type default)
			)
			(layer "F.Fab")
		)
		(fp_line
			(start -0.12065 -0.305054)
			(end -0.12065 -0.2794)
			(stroke
				(width 0.1)
				(type default)
			)
			(layer "F.Fab")
		)
		(fp_line
			(start -0.67945 0.3048)
			(end -0.67945 -0.305054)
			(stroke
				(width 0.1)
				(type default)
			)
			(layer "F.Fab")
		)
		(fp_line
			(start -0.67945 -0.305054)
			(end -0.12065 -0.305054)
			(stroke
				(width 0.1)
				(type default)
			)
			(layer "F.Fab")
		)
		(pad "1" smd circle
			(at -0.40005 0 180)
			(size 0 0)
			(layers "F.Cu" "F.Mask" "F.Paste")
			(net "NCSI_BMC_RXD0_R")
		)
		(pad "2" smd circle
			(at 0.40005 0 180)
			(size 0 0)
			(layers "F.Cu" "F.Mask" "F.Paste")
			(net "RMII_OCP_BMC_RXD_0")
		)
	)
)
